# T6G (Grand Teton) — schematic netlist excerpt (pin names and nets, part order shuffled) for the footprints in the layout excerpt that follows; sources: Cadence DE-HDL packaged netlist, KiCad conversion of 04192023_DAF0TMB3IC0_F0TG_MB_C_brd_V02_OCP.brd

R1748  Q_RES  10K 1% EMPTY  pkg 0402LF  page 171 : A = JTAG_SCM_MUX_TCK ; B = GND

Q130  MOSFET_NCH_DUAL  PJT138K IC  pkg SOT363XD  page 125
  S1  = GND
  G1  = GPU_3V3IO_RSVD3_FFU
  D2  = GPU_3V3IO_RSVD3_FFU_ISO
  S2  = GND
  G2  = GPU_3V3IO_RSVD3_FFU_N
  D1  = GPU_3V3IO_RSVD3_FFU_N

(kicad_pcb
	(version 20260206)
	(generator "pcbnew")
	(generator_version "10.0")
	(general
		(thickness 1.6)
		(legacy_teardrops no)
	)
	(paper "A4")
	(title_block
		(title "04192023_DAF0TMB3IC0_F0TG_MB_C_brd_V02_OCP.brd")
		(comment 1 "Grand Teton / footprints 2808-2809 of 8354")
	)
	(layers
		(0 "F.Cu" signal "TOP")
		(4 "In1.Cu" signal "GND")
		(6 "In2.Cu" signal "IN1")
		(8 "In3.Cu" signal "GND1")
		(10 "In4.Cu" signal "IN2")
		(12 "In5.Cu" signal "GND2")
		(14 "In6.Cu" signal "IN3")
		(16 "In7.Cu" signal "GND3")
		(18 "In8.Cu" signal "VCC")
		(20 "In9.Cu" signal "VCC1")
		(22 "In10.Cu" signal "GND4")
		(24 "In11.Cu" signal "IN4")
		(26 "In12.Cu" signal "GND5")
		(28 "In13.Cu" signal "IN5")
		(30 "In14.Cu" signal "GND6")
		(32 "In15.Cu" signal "IN6")
		(34 "In16.Cu" signal "GND7")
		(2 "B.Cu" signal "BOTTOM")
		(9 "F.Adhes" user "F.Adhesive")
		(11 "B.Adhes" user "B.Adhesive")
		(13 "F.Paste" user "Package Geometry/Pastemask Top")
		(15 "B.Paste" user "Package Geometry/Pastemask Bottom")
		(5 "F.SilkS" user "Ref Des/Silkscreen Top")
		(7 "B.SilkS" user "Ref Des/Silkscreen Bottom")
		(1 "F.Mask" user "Board Geometry/Soldermask Top")
		(3 "B.Mask" user "Board Geometry/Soldermask Bottom")
		(17 "Dwgs.User" user "User.Drawings")
		(19 "Cmts.User" user "User.Comments")
		(21 "Eco1.User" user "User.Eco1")
		(23 "Eco2.User" user "User.Eco2")
		(25 "Edge.Cuts" user "Board Geometry/Outline")
		(27 "Margin" user)
		(31 "F.CrtYd" user "Package Geometry/Place Bound Top")
		(29 "B.CrtYd" user "Package Geometry/Place Bound Bottom")
		(35 "F.Fab" user "Ref Des/Assembly Top")
		(33 "B.Fab" user "Ref Des/Assembly Bottom")
	)
	(footprint ""
		(layer "F.Cu")
		(at 303.573434 -427.1391 -90)
		(property "Reference" "Q130"
			(at 1.471676 -1.958848 90)
			(unlocked yes)
			(layer "F.SilkS")
			(effects
				(font
					(size 0.7874 0.5842)
					(thickness 0.1524)
				)
				(justify left)
			)
		)
		(property "Value" ""
			(at 0 0 270)
			(layer "F.Fab")
			(effects
				(font
					(size 1.27 1.27)
				)
			)
		)
		(duplicate_pad_numbers_are_jumpers no)
		(fp_line
			(start -1.332738 1.100074)
			(end -1.332738 -1.100074)
			(stroke
				(width 0.1524)
				(type default)
			)
			(layer "F.SilkS")
		)
		(fp_line
			(start 1.332738 1.100074)
			(end -1.332738 1.100074)
			(stroke
				(width 0.1524)
				(type default)
			)
			(layer "F.SilkS")
		)
		(fp_line
			(start 0 -0.541274)
			(end 0.4826 -1.100074)
			(stroke
				(width 0.1524)
				(type default)
			)
			(layer "F.SilkS")
		)
		(fp_line
			(start -1.332738 -1.100074)
			(end -0.4826 -1.100074)
			(stroke
				(width 0.1524)
				(type default)
			)
			(layer "F.SilkS")
		)
		(fp_line
			(start -0.4826 -1.100074)
			(end 0 -0.541274)
			(stroke
				(width 0.1524)
				(type default)
			)
			(layer "F.SilkS")
		)
		(fp_line
			(start 0.4826 -1.100074)
			(end 1.332738 -1.100074)
			(stroke
				(width 0.1524)
				(type default)
			)
			(layer "F.SilkS")
		)
		(fp_line
			(start 1.332738 -1.100074)
			(end 1.332738 1.100074)
			(stroke
				(width 0.1524)
				(type default)
			)
			(layer "F.SilkS")
		)
		(fp_poly
			(pts
				(xy -1.542542 -1.16332) (xy -2.287016 -1.411478) (xy -1.7907 -1.908048)
			)
			(stroke
				(width 0)
				(type default)
			)
			(fill yes)
			(layer "F.SilkS")
		)
		(fp_line
			(start -0.674878 1.100074)
			(end -0.674878 -1.100074)
			(stroke
				(width 0.1)
				(type default)
			)
			(layer "F.Fab")
		)
		(fp_line
			(start 0.674878 1.100074)
			(end -0.674878 1.100074)
			(stroke
				(width 0.1)
				(type default)
			)
			(layer "F.Fab")
		)
		(fp_line
			(start -0.674878 -1.100074)
			(end 0.674878 -1.100074)
			(stroke
				(width 0.1)
				(type default)
			)
			(layer "F.Fab")
		)
		(fp_line
			(start 0.674878 -1.100074)
			(end 0.674878 1.100074)
			(stroke
				(width 0.1)
				(type default)
			)
			(layer "F.Fab")
		)
		(fp_poly
			(pts
				(xy -2.2352 -0.298958) (xy -2.2352 -1.001014) (xy -1.533144 -0.649986)
			)
			(stroke
				(width 0)
				(type default)
			)
			(fill yes)
			(layer "F.Fab")
		)
		(pad "1" smd rect
			(at -0.94996 -0.649986)
			(size 0.4318 0.508)
			(layers "F.Cu" "F.Mask" "F.Paste")
			(net "GND")
		)
		(pad "2" smd rect
			(at -0.94996 0)
			(size 0.4318 0.508)
			(layers "F.Cu" "F.Mask" "F.Paste")
			(net "GPU_3V3IO_RSVD3_FFU")
		)
		(pad "3" smd rect
			(at -0.94996 0.649986)
			(size 0.4318 0.508)
			(layers "F.Cu" "F.Mask" "F.Paste")
			(net "GPU_3V3IO_RSVD3_FFU_ISO")
		)
		(pad "4" smd rect
			(at 0.94996 0.649986)
			(size 0.4318 0.508)
			(layers "F.Cu" "F.Mask" "F.Paste")
			(net "GND")
		)
		(pad "5" smd rect
			(at 0.94996 0)
			(size 0.4318 0.508)
			(layers "F.Cu" "F.Mask" "F.Paste")
			(net "GPU_3V3IO_RSVD3_FFU_N")
		)
		(pad "6" smd rect
			(at 0.94996 -0.649986)
			(size 0.4318 0.508)
			(layers "F.Cu" "F.Mask" "F.Paste")
			(net "GPU_3V3IO_RSVD3_FFU_N")
		)
	)
	(footprint ""
		(layer "F.Cu")
		(at 118.718584 -61.916056 180)
		(property "Reference" "R1748"
			(at 0 0 180)
			(layer "F.SilkS")
			(hide yes)
			(effects
				(font
					(size 1.27 1.27)
				)
			)
		)
		(property "Value" ""
			(at 0 0 180)
			(layer "F.Fab")
			(effects
				(font
					(size 1.27 1.27)
				)
			)
		)
		(duplicate_pad_numbers_are_jumpers no)
		(fp_line
			(start 0.7874 0.4064)
			(end -0.7874 0.4064)
			(stroke
				(width 0.1524)
				(type default)
			)
			(layer "F.SilkS")
		)
		(fp_line
			(start 0.7874 -0.4064)
			(end 0.7874 0.4064)
			(stroke
				(width 0.1524)
				(type default)
			)
			(layer "F.SilkS")
		)
		(fp_line
			(start -0.7874 0.4064)
			(end -0.7874 -0.4064)
			(stroke
				(width 0.1524)
				(type default)
			)
			(layer "F.SilkS")
		)
		(fp_line
			(start -0.7874 -0.4064)
			(end 0.7874 -0.4064)
			(stroke
				(width 0.1524)
				(type default)
			)
			(layer "F.SilkS")
		)
		(fp_line
			(start 0.67945 0.3048)
			(end 0.120396 0.3048)
			(stroke
				(width 0.1)
				(type default)
			)
			(layer "F.Fab")
		)
		(fp_line
			(start 0.67945 -0.3048)
			(end 0.67945 0.3048)
			(stroke
				(width 0.1)
				(type default)
			)
			(layer "F.Fab")
		)
		(fp_line
			(start 0.12065 -0.2794)
			(end 0.12065 -0.3048)
			(stroke
				(width 0.1)
				(type default)
			)
			(layer "F.Fab")
		)
		(fp_line
			(start 0.12065 -0.3048)
			(end 0.67945 -0.3048)
			(stroke
				(width 0.1)
				(type default)
			)
			(layer "F.Fab")
		)
		(fp_line
			(start 0.120396 0.3048)
			(end 0.120396 0.2794)
			(stroke
				(width 0.1)
				(type default)
			)
			(layer "F.Fab")
		)
		(fp_line
			(start 0.120396 0.2794)
			(end -0.12065 0.2794)
			(stroke
				(width 0.1)
				(type default)
			)
			(layer "F.Fab")
		)
		(fp_line
			(start -0.12065 0.3048)
			(end -0.67945 0.3048)
			(stroke
				(width 0.1)
				(type default)
			)
			(layer "F.Fab")
		)
		(fp_line
			(start -0.12065 0.2794)
			(end -0.12065 0.3048)
			(stroke
				(width 0.1)
				(type default)
			)
			(layer "F.Fab")
		)
		(fp_line
			(start -0.12065 -0.2794)
			(end 0.12065 -0.2794)
			(stroke
				(width 0.1)
				(type default)
			)
			(layer "F.Fab")
		)
		(fp_line
			(start -0.12065 -0.305054)
			(end -0.12065 -0.2794)
			(stroke
				(width 0.1)
				(type default)
			)
			(layer "F.Fab")
		)
		(fp_line
			(start -0.67945 0.3048)
			(end -0.67945 -0.305054)
			(stroke
				(width 0.1)
				(type default)
			)
			(layer "F.Fab")
		)
		(fp_line
			(start -0.67945 -0.305054)
			(end -0.12065 -0.305054)
			(stroke
				(width 0.1)
				(type default)
			)
			(layer "F.Fab")
		)
		(pad "1" smd circle
			(at -0.40005 0 180)
			(size 0 0)
			(layers "F.Cu" "F.Mask" "F.Paste")
			(net "JTAG_SCM_MUX_TCK")
		)
		(pad "2" smd circle
			(at 0.40005 0 180)
			(size 0 0)
			(layers "F.Cu" "F.Mask" "F.Paste")
			(net "GND")
		)
	)
)
